FILE_TYPE = CONNECTIVITY;
{Allegro Design Entry HDL 16.6-p007 (v16-6-112F) 10/10/2012}
"PAGE_NUMBER" = 209;
0"NC";
1"GND\g";
2"PVCCIN_CPU1\g";
3"VR_FET_SW_P12V_STBY_PVCCIN_CPU1\g";
4"GND\g";
5"GND\g";
6"GND\g";
7"GND\g";
8"PVCCIN_CPU1\g";
9"VR_FET_SW_P12V_STBY_PVCCIN_CPU1\g";
10"P12V_STBY\g";
11"P5V_STBY\g";
12"GND\g";
13"GND\g";
14"GND\g";
15"A_TSENSE_PVCCIN_CPU1";
16"VR_PVCCIN_CPU1_PH5_VCIN"VOLTAGE"5";
17"VR_PVCCIN_CPU1_PHASE5_RC";
18"VR_PVCCIN_CPU1_PH5_BOOT_R";
19"TP_PVCCIN_CPU1_PH5_GL_0";
20"VR_PVCCIN_CPU1_PH5_PHASE"VOLTAGE"5";
21"TP_PVCCIN_CPU1_PH5_GL_1";
22"VSENSE_PVCCIN_CPU1_N";
23"VSENSE_PVCCIN_CPU1_SKT_VRTN";
24"VSENSE_PVCCIN_CPU1_SKT_VSEN";
25"VSENSE_PVCCIN_CPU1_P";
26"VR_PVCCIN_CPU1_AIREF5";
27"VR_PVCCIN_CPU1_PHASE5"VOLTAGE"5";
28"VR_PVCCIN_CPU1_PH5_OCSET";
29"ISENSE_PVCCIN_CPU1_PH5_IMON";
30"VR_PVCCIN_CPU1_PH5_BOOT";
31"VR_PVCCIN_CPU1_PWM5"VOLTAGE"3.6";
32"GND\g";
%"RES"
"1","(-5475,1450)","0","mstr_discrete","I10";
;
MATERIAL"CHIP"
WATTAGE"1/16W"
PART_NUMBER"G21497-005"
TOLERANCE"5%"
VALUE"0.0"
LOCATION"R1E7"
PACK_TYPE"0402"
BOM_COST"PROC_VRD_VCCIN_CPU0"
CDS_SEC"1"
$SEC"1"
ROOM"PVCCIN_CPU1_VSENSE_VR"
CDS_LIB"mstr_discrete"
CDS_LOCATION"R1E7";
"B"
$PN"2"23;
"A"
$PN"1"22;
%"RES"
"1","(-5500,1900)","0","mstr_discrete","I11";
;
TOLERANCE"5%"
LOCATION"R1E6"
VALUE"0.0"
MATERIAL"CHIP"
PACK_TYPE"0402"
WATTAGE"1/16W"
PART_NUMBER"G21497-005"
BOM_COST"PROC_VRD_VCCIN_CPU0"
CDS_SEC"1"
$SEC"1"
CDS_LIB"mstr_discrete"
ROOM"PVCCIN_CPU1_VSENSE_VR"
CDS_LOCATION"R1E6";
"B"
$PN"2"24;
"A"
$PN"1"25;
%"GND"
"1","(-4825,775)","0","mstr_symbols","I12";
;
VOLTAGE"0"
CDS_LIB"mstr_symbols"
SIZE"1B"
BOM_COST"PROC_VRD_VCCIN_CPU0"
ROOM"PVCCIN_CPU1_VSENSE_VR"
BODY_TYPE"PLUMBING"
HDL_POWER"GND";
"A\NAC"1;
%"RES"
"1","(-5500,2300)","0","mstr_discrete","I15";
;
PART_NUMBER"G21796-017"
LOCATION"R1E4"
TOLERANCE"1%"
PACK_TYPE"0402"
WATTAGE"1/16W"
VALUE"100.0"
ROOM"PVCCIN_CPU1_VSENSE_VR"
$SEC"1"
CDS_LOCATION"R1E4"
CDS_SEC"1"
BOM_COST"PROC_VRD_VCCIN_CPU0"
CDS_LIB"mstr_discrete"
MATERIAL"CHIP";
"B"
$PN"2"2;
"A"
$PN"1"25;
%"CAP"
"1","(-6225,4025)","0","mstr_discrete","I16";
;
CDS_SEC"1"
CDS_LOCATION"C1C26"
LOCATION"C1C26"
VALUE"1.0UF"
PART_NUMBER"D97712-011"
TOLERANCE"10%"
MATERIAL"X6S"
PACK_TYPE"0402"
VOLTAGE"16V"
SEC_TYPE"0402"
SEC"1"
ROOM"PVCCIN_CPU1_PWR_VR"
CDS_LIB"mstr_discrete";
"A"
$PN"1"3;
"B"
$PN"2"6;
%"CAP_A"
"1","(-5925,4025)","0","dev_discrete","I17";
;
CDS_LOCATION"C1C25"
VALUE"0.1UF"
LOCATION"C1C25"
VOLTAGE"16V"
PART_NUMBER"A36096-030"
MATERIAL"X7R"
TOLERANCE"10%"
PACK_TYPE"0402V"
CDS_LIB"dev_discrete"
SEC"1"
SEC_TYPE"0402V"
CDS_SEC"1"
ROOM"PVCCIN_CPU1_PWR_VR";
"B"
$PN"2"6;
"A"
$PN"1"3;
%"CAP"
"1","(-5625,4025)","0","mstr_discrete","I18";
;
CDS_SEC"1"
CDS_LOCATION"C1D32"
VALUE"1.0UF"
LOCATION"C1D32"
PART_NUMBER"D97712-011"
VOLTAGE"16V"
TOLERANCE"10%"
PACK_TYPE"0402"
MATERIAL"X6S"
SEC_TYPE"0402"
SEC"1"
ROOM"PVCCIN_CPU1_PWR_VR"
CDS_LIB"mstr_discrete";
"A"
$PN"1"16;
"B"
$PN"2"6;
%"PVCCIN_CPU1"
"1","(-4650,2450)","0","mstr_symbols","I19";
;
VOLTAGE"2.0V"
CDS_LIB"mstr_symbols"
BODY_TYPE"PLUMBING"
HDL_POWER"PVCCIN_CPU1";
"G\NAC"2;
%"CAP"
"1","(-5900,3450)","2","mstr_discrete","I20";
;
CDS_SEC"1"
PACK_TYPE"0402"
LOCATION"C1C24"
VOLTAGE"16V"
TOLERANCE"10%"
MATERIAL"X7R"
PART_NUMBER"A36096-104"
VALUE"0.220UF"
CDS_LOCATION"C1C24"
CDS_LIB"mstr_discrete"
ROOM"PVCCIN_CPU1_PWR_VR"
NO_XNET_CONNECTION"1"
SEC"1"
SPOF"TRUE"
SEC_TYPE"0402";
"A"
$PN"1"30;
"B"
$PN"2"20;
%"CAP"
"1","(-4800,4025)","0","mstr_discrete","I22";
;
CDS_SEC"1"
CDS_LOCATION"C1D33"
LOCATION"C1D33"
VALUE"0.22UF"
VOLTAGE"16V"
TOLERANCE"10%"
PART_NUMBER"A36096-155"
PACK_TYPE"0402"
MATERIAL"X7R"
CDS_LIB"mstr_discrete"
ROOM"PVCCIN_CPU1_PWR_VR"
SEC"1"
SEC_TYPE"0402";
"A"
$PN"1"11;
"B"
$PN"2"6;
%"VCC_CORE"
"1","(-6350,4450)","0","mstr_symbols","I23";
;
HDL_POWER"VR_FET_SW_P12V_STBY_PVCCIN_CPU1"
CDS_LIB"mstr_symbols";
"A"3;
%"RES"
"2","(-6300,1700)","0","mstr_discrete","I3";
;
PART_NUMBER"G21796-026"
MATERIAL"EMPTY"
LOCATION"R1E5"
VALUE"1.00K"
PACK_TYPE"0402"
WATTAGE"1/16W"
TOLERANCE"1%"
BOM_COST"PROC_VRD_VCCIN_CPU0"
CDS_SEC"1"
$SEC"1"
CDS_LOCATION"R1E5"
ROOM"PVCCIN_CPU1_VSENSE_VR"
CDS_LIB"mstr_discrete";
"A"
$PN"1"25;
"B"
$PN"2"22;
%"GND"
"1","(-2675,3125)","0","mstr_symbols","I34";
;
CDS_LIB"mstr_symbols"
SIZE"1B"
VOLTAGE"0"
BOM_COST"PROC_VRD_VCCIN_CPU0"
ROOM"PVCCIN_CPU1_PWR_VR"
BODY_TYPE"PLUMBING"
HDL_POWER"GND";
"A\NAC"4;
%"CAPP"
"1","(-1425,2075)","0","mstr_discrete","I35";
;
CDS_SEC"1"
VALUE"270UF"
LOCATION"C1C1"
TOLERANCE"20%"
VOLTAGE"16V"
PACK_TYPE"2626"
MATERIAL"OSCON"
PART_NUMBER"A31228-047"
SEC_TYPE"2626"
SEC"1"
CDS_LOCATION"C1C1"
ROOM"PVCCIN_CPU1_FILTER_VR"
CDS_LIB"mstr_discrete";
"B"
$PN"2"5;
"A"
$PN"1"9;
%"GND"
"1","(-1200,1650)","0","mstr_symbols","I36";
;
SIZE"1B"
VOLTAGE"0"
CDS_LIB"mstr_symbols"
ROOM"PVCCIN_CPU1_FILTER_VR"
BOM_COST"PROC_VRD_VCCIN_CPU0"
BODY_TYPE"PLUMBING"
HDL_POWER"GND";
"A\NAC"5;
%"CAPP"
"1","(-950,2050)","0","mstr_discrete","I37";
;
CDS_SEC"1"
PART_NUMBER"A31228-047"
MATERIAL"OSCON"
VOLTAGE"16V"
TOLERANCE"20%"
PACK_TYPE"2626"
VALUE"270UF"
LOCATION"C1E18"
ROOM"PVCCIN_CPU1_FILTER_VR"
SEC"1"
SEC_TYPE"2626"
CDS_LOCATION"C1E18"
CDS_LIB"mstr_discrete";
"B"
$PN"2"5;
"A"
$PN"1"9;
%"CAPP"
"1","(-600,2050)","0","mstr_discrete","I38";
;
CDS_SEC"1"
PART_NUMBER"A31228-047"
MATERIAL"OSCON"
VOLTAGE"16V"
TOLERANCE"20%"
PACK_TYPE"2626"
VALUE"270UF"
LOCATION"C1C2"
SEC"1"
SEC_TYPE"2626"
ROOM"PVCCIN_CPU1_FILTER_VR"
CDS_LIB"mstr_discrete"
CDS_LOCATION"C1C2";
"B"
$PN"2"5;
"A"
$PN"1"9;
%"GND"
"1","(-6850,3525)","0","mstr_symbols","I4";
;
ROOM"PVCCIN_CPU1_PWR_VR"
CDS_LIB"mstr_symbols"
VOLTAGE"0"
BOM_COST"PROC_VRD_VCCIN_CPU0"
SIZE"1B"
BODY_TYPE"PLUMBING"
HDL_POWER"GND";
"A\NAC"6;
%"GND"
"1","(-350,2925)","0","mstr_symbols","I41";
;
VOLTAGE"0"
CDS_LIB"mstr_symbols"
SIZE"1B"
BOM_COST"PROC_VRD_VCCIN_CPU0"
ROOM"PVCCIN_CPU1_PWR_VR"
BODY_TYPE"PLUMBING"
HDL_POWER"GND";
"A\NAC"7;
%"CAP_A"
"1","(-750,3250)","0","dev_discrete","I42";
;
PART_NUMBER"E15431-004"
PACK_TYPE"0603V"
MATERIAL"X6S"
TOLERANCE"20%"
VOLTAGE"4V"
LOCATION"C1D24"
VALUE"22.0UF"
GROUP"PWR_MLCC_CAP"
CDS_LIB"dev_discrete"
CDS_LOCATION"C1D24"
ROOM"PVCCIN_CPU1_PWR_VR"
SEC"1"
SEC_TYPE"0603V"
CDS_SEC"1"
BOM_COST"PROC_VRD_VCCIN_CPU0";
"B"
$PN"2"7;
"A"
$PN"1"8;
%"PVCCIN_CPU1"
"1","(-350,3575)","0","mstr_symbols","I43";
;
CDS_LIB"mstr_symbols"
VOLTAGE"2.0V"
BODY_TYPE"PLUMBING"
HDL_POWER"PVCCIN_CPU1";
"G\NAC"8;
%"VCC_CORE"
"1","(-600,2525)","0","mstr_symbols","I45";
;
HDL_POWER"VR_FET_SW_P12V_STBY_PVCCIN_CPU1"
CDS_LIB"mstr_symbols";
"A"9;
%"CAP"
"1","(-7125,4025)","0","mstr_discrete","I5";
;
CDS_SEC"1"
CDS_LOCATION"C9N27"
PART_NUMBER"C95333-007"
VOLTAGE"16V"
LOCATION"C9N27"
VALUE"10UF"
MATERIAL"X6S"
PACK_TYPE"0805"
TOLERANCE"10%"
CDS_LIB"mstr_discrete"
ROOM"PVCCIN_CPU1_PWR_VR"
SEC"1"
SEC_TYPE"0805";
"A"
$PN"1"3;
"B"
$PN"2"6;
%"P12V_STBY"
"1","(-3350,2475)","0","mstr_symbols","I53";
;
SIZE"1B"
CDS_LIB"mstr_symbols"
VOLTAGE"12.0V"
BODY_TYPE"PLUMBING"
HDL_POWER"P12V_STBY";
"G\NAC"10;
%"P5V_STBY"
"1","(-4550,4750)","0","mstr_symbols","I54";
;
CDS_LIB"mstr_symbols"
SIZE"1B"
VOLTAGE"5.0V"
BODY_TYPE"PLUMBING"
HDL_POWER"P5V_STBY";
"G\NAC"11;
%"CAP_A"
"1","(-350,3250)","0","dev_discrete","I55";
;
MATERIAL"X6S"
PACK_TYPE"0603V"
VALUE"22.0UF"
VOLTAGE"4V"
TOLERANCE"20%"
PART_NUMBER"E15431-004"
LOCATION"C9P20"
GROUP"PWR_MLCC_CAP"
CDS_LIB"dev_discrete"
CDS_LOCATION"C9P20"
SEC"1"
SEC_TYPE"0603V"
CDS_SEC"1";
"B"
$PN"2"7;
"A"
$PN"1"8;
%"IR354XX"
"1","(-3250,3775)","0","mstr_discrete","I56";
;
CDS_SEC"1"
MATERIAL"IC"
LOCATION"EU1C3"
PART_NUMBER"H73688-001"
CDS_LIB"mstr_discrete"
CDS_LOCATION"EU1C3"
ROOM"PVCCIN_CPU1_PWR_VR"
PACK_TYPE"SM"
SEC"1"
SEC_TYPE"SM"
VALUE"IR35411";
"TOUT_FLT"
$PN"36"15;
"NC"
$PN"31"0;
"OCSET"
$PN"37"28;
"IOUT"
$PN"38"29;
"SW"
$PN"10"27;
"BOOST"
$PN"33"18;
"REFIN"
$PN"39"26;
"PWM"
$PN"34"31;
"PHASE"
$PN"32"20;
"VIN<0>"
$PN"25"3;
"VCC"
$PN"3"16;
"VIN<1>"
$PN"30"3;
"EN"
$PN"35"11;
"VDRV"
$PN"4"11;
"VOS"
$PN"1"8;
"LGND"
$PN"2"4;
"PGND<1>"
$PN"7"4;
"PGND<2>"
$PN"40"4;
"PGND<0>"
$PN"5"4;
"GL<0>"
$PN"6"19;
"GL<1>"
$PN"41"21;
%"RES"
"2","(-1000,3925)","0","mstr_discrete","I59";
;
CDS_LOCATION"R1D52"
PART_NUMBER"G21796-187"
LOCATION"R1D52"
VALUE"68.1K"
TOLERANCE"1%"
WATTAGE"1/16W"
MATERIAL"EMPTY"
PACK_TYPE"0402"
$SEC"1"
CDS_SEC"1"
CDS_LIB"mstr_discrete";
"A"
$PN"1"28;
"B"
$PN"2"12;
%"GND"
"1","(-1000,3750)","0","mstr_symbols","I60";
;
ROOM"PVCCIN_CPU1_FILTER_VR"
BOM_COST"PROC_VRD_VCCIN_CPU0"
SIZE"1B"
CDS_LIB"mstr_symbols"
VOLTAGE"0"
BODY_TYPE"PLUMBING"
HDL_POWER"GND";
"A\NAC"12;
%"CAP_A"
"1","(-3950,3275)","0","dev_discrete","I62";
;
CDS_SEC"1"
CDS_LOCATION"CT13"
LOCATION"CT13"
PART_NUMBER"A36096-030"
PACK_TYPE"0402V"
POP"NOPOP"
VALUE"0.1UF"
TOLERANCE"10%"
VOLTAGE"16V"
MATERIAL"X7R"
SEC_TYPE"0402V"
SEC"1"
CDS_LIB"dev_discrete"
ROOM"PVCCIN_CPU0_PWR_VR";
"B"
$PN"2"13;
"A"
$PN"1"26;
%"GND"
"1","(-3950,3025)","0","mstr_symbols","I63";
;
CDS_LIB"mstr_symbols"
VOLTAGE"0"
SIZE"1B"
BOM_COST"PROC_VRD_VCCIN_CPU0"
ROOM"PVCCIN_CPU0_PWR_VR"
BODY_TYPE"PLUMBING"
HDL_POWER"GND";
"A\NAC"13;
%"GND"
"1","(-2400,2800)","0","mstr_symbols","I65";
;
CDS_LIB"mstr_symbols"
SIZE"1B"
VOLTAGE"0"
BOM_COST"PROC_VRD_VCCIN_CPU0"
ROOM"PVCCIN_CPU0_PWR_VR"
BODY_TYPE"PLUMBING"
HDL_POWER"GND";
"A\NAC"32;
%"CAP"
"1","(-1950,3825)","0","mstr_discrete","I67";
;
CDS_SEC"1"
CDS_LOCATION"CT15"
VALUE"1000PF"
POP"NOPOP"
LOCATION"CT15"
TOLERANCE"10%"
MATERIAL"X7R"
PART_NUMBER"A36096-046"
PACK_TYPE"0402LF"
VOLTAGE"50V"
SEC_TYPE"0402LF"
SEC"1"
CDS_LIB"mstr_discrete"
ROOM"VDDQ_KLM_PWR_VR";
"A"
$PN"1"15;
"B"
$PN"2"14;
%"GND"
"1","(-1950,3575)","0","mstr_symbols","I68";
;
CDS_LIB"mstr_symbols"
SIZE"1B"
VOLTAGE"0"
ROOM"VDDQ_KLM_PWR_VR"
BODY_TYPE"PLUMBING"
HDL_POWER"GND";
"A\NAC"14;
%"CAP"
"1","(-6850,4025)","0","mstr_discrete","I7";
;
CDS_SEC"1"
CDS_LOCATION"C9N26"
LOCATION"C9N26"
VALUE"10UF"
VOLTAGE"16V"
PART_NUMBER"C95333-007"
PACK_TYPE"0805"
MATERIAL"X6S"
TOLERANCE"10%"
CDS_LIB"mstr_discrete"
ROOM"PVCCIN_CPU1_PWR_VR"
SEC"1"
SEC_TYPE"0805";
"A"
$PN"1"3;
"B"
$PN"2"6;
%"CAP"
"1","(-2400,3300)","0","mstr_discrete","I73";
;
CDS_SEC"1"
CDS_LOCATION"CT14"
TOLERANCE"10%"
VALUE"1000PF"
LOCATION"CT14"
PART_NUMBER"A36096-046"
PACK_TYPE"0402LF"
POP"NOPOP"
VOLTAGE"50V"
MATERIAL"X7R"
SEC_TYPE"0402LF"
SEC"1"
ROOM"VDDQ_KLM_PWR_VR"
CDS_LIB"mstr_discrete";
"A"
$PN"1"27;
"B"
$PN"2"17;
%"RES"
"1","(-4800,3575)","0","mstr_discrete","I75";
;
CDS_SEC"1"
CDS_LOCATION"RT9"
TOLERANCE"5.0%"
PART_NUMBER"G22178-002"
PACK_TYPE"0603"
WATTAGE"1/10W"
MATERIAL"CHIP"
LOCATION"RT9"
VALUE"0"
SEC_TYPE"0603"
SEC"1"
ROOM"NIC_SPRV"
BOM_COST"NT_GBE_BASE"
CDS_LIB"mstr_discrete";
"B"
$PN"2"18;
"A"
$PN"1"30;
%"RES"
"1","(-5425,4650)","0","mstr_discrete","I79";
;
WATTAGE"1/16W"
PACK_TYPE"0402"
PART_NUMBER"G21497-005"
MATERIAL"CHIP"
LOCATION"R9P32"
TOLERANCE"5%"
VALUE"0.0"
CDS_LOCATION"R9P32"
CDS_SEC"1"
ROOM"CPU0"
SEC"1"
SEC_TYPE"0402"
CDS_LIB"mstr_discrete"
BOM_COST"PROC_SIDEBAND";
"B"
$PN"2"11;
"A"
$PN"1"16;
%"CAP"
"1","(-6550,4025)","0","mstr_discrete","I8";
;
CDS_SEC"1"
CDS_LOCATION"C9N25"
PART_NUMBER"C95333-007"
PACK_TYPE"0805"
MATERIAL"X6S"
LOCATION"C9N25"
TOLERANCE"10%"
VALUE"10UF"
VOLTAGE"16V"
CDS_LIB"mstr_discrete"
ROOM"PVCCIN_CPU1_PWR_VR"
SEC"1"
SEC_TYPE"0805";
"A"
$PN"1"3;
"B"
$PN"2"6;
%"IND-120NH-30-GP"
"1","(-1400,3500)","1","w_hdl","I80";
;
CDS_SEC"1"
CDS_LOCATION"L1C2"
VALUE"IND-120NH-30-GP"
LOCATION"L1C2"
ATTRIBUTE"120NH"
RATED"ISAT=94A@25C"
PACK_SIZE"DCR=0.17MOHM"
TYPE"IRMS=66A@DELTA_T<40C"
PART_NUMBER"068.1202N.M001"
CDS_LIB"w_hdl"
CDS_LMAN_SYM_OUTLINE"-75,100,75,-100"
SEC_TYPE"DISCRET-GB2"
SEC"1"
PACK_TYPE"DISCRET-GB2";
"F"
$PN"2"8;
"S"
$PN"1"27;
%"IND-80NH-1-GP"
"1","(-3050,2275)","1","w_hdl","I81";
;
CDS_SEC"1"
CDS_LOCATION"L1B2"
VALUE"IND-80NH-1-GP"
LOCATION"L1B2"
ATTRIBUTE"80NH"
RATED"ISAT=50A@25C"
PACK_SIZE"DCR=0.22MOHM"
TYPE"IRMS=34A@DELTA_T<45C"
PACK_TYPE"DISCRET-GC2"
SEC"1"
SEC_TYPE"DISCRET-GC2"
CDS_LMAN_SYM_OUTLINE"-75,100,75,-100"
CDS_LIB"w_hdl"
PART_NUMBER"068.8001N.M001";
"F"
$PN"2"9;
"S"
$PN"1"10;
%"SC1U10V2KX-4-GP"
"1","(-5125,4025)","0","w_hdl","I89";
;
CDS_SEC"1"
CDS_LOCATION"C1C18"
LOCATION"C1C18"
RATED"10V"
TOLERANCE"10%"
ATTRIBUTE"1UF"
VALUE"SC1U10V2KX-4-GP"
PACK_SIZE"0402"
PACK_TYPE"SMD-BCG6"
SEC"1"
SEC_TYPE"SMD-BCG6"
CDS_LMAN_SYM_OUTLINE"-50,25,50,-25"
CDS_LIB"w_hdl"
PART_NUMBER"78.10523.8FL";
"2"
$PN"2"6;
"1"
$PN"1"11;
%"RES"
"1","(-5475,1050)","0","mstr_discrete","I9";
;
PART_NUMBER"G21796-017"
LOCATION"R1E8"
VALUE"100.0"
TOLERANCE"1%"
PACK_TYPE"0402"
WATTAGE"1/16W"
CDS_SEC"1"
$SEC"1"
CDS_LIB"mstr_discrete"
CDS_LOCATION"R1E8"
BOM_COST"PROC_VRD_VCCIN_CPU0"
ROOM"PVCCIN_CPU1_VSENSE_VR"
MATERIAL"CHIP";
"B"
$PN"2"1;
"A"
$PN"1"22;
%"1R3F-GP"
"1","(-2400,2975)","0","w_hdl","I90";
;
CDS_SEC"1"
CDS_LOCATION"RT10"
PACK_SIZE"0603"
RATED"1/10W"
LOCATION"RT10"
VALUE"1R3F-GP"
ATTRIBUTE"1 OHM"
POP"NOPOP"
TOLERANCE"1%"
PACK_TYPE"RCL_GP"
SEC"1"
SEC_TYPE"RCL_GP"
PART_NUMBER"64.1R005.55L"
CDS_LIB"w_hdl"
CDS_LMAN_SYM_OUTLINE"-50,75,50,-75";
"2"
$PN"2"32;
"1"
$PN"1"17;
END.
